(kicad_pcb
	(version 20241229)
	(generator "pcbnew")
	(generator_version "9.0")
	(general
		(thickness 1.62)
		(legacy_teardrops no)
	)
	(paper "A3")
	(title_block
		(title "COM Express 7 Baseboard")
		(date "2025-02-04")
		(rev "1.1.2")
		(company "Antmicro Ltd")
		(comment 1 "www.antmicro.com")
		(comment 9 "footprint 489 of 802 (J12), pads 205-245 of 450")
	)
	(layers
		(0 "F.Cu" signal)
		(4 "In1.Cu" signal)
		(6 "In2.Cu" signal)
		(8 "In3.Cu" signal)
		(10 "In4.Cu" signal)
		(12 "In5.Cu" signal)
		(14 "In6.Cu" signal)
		(2 "B.Cu" signal)
		(9 "F.Adhes" user "F.Adhesive")
		(11 "B.Adhes" user "B.Adhesive")
		(13 "F.Paste" user)
		(15 "B.Paste" user)
		(5 "F.SilkS" user "F.Silkscreen")
		(7 "B.SilkS" user "B.Silkscreen")
		(1 "F.Mask" user)
		(3 "B.Mask" user)
		(17 "Dwgs.User" user "User.Drawings")
		(19 "Cmts.User" user "User.Comments")
		(21 "Eco1.User" user "User.Eco1")
		(23 "Eco2.User" user "User.Eco2")
		(25 "Edge.Cuts" user)
		(27 "Margin" user)
		(31 "F.CrtYd" user "F.Courtyard")
		(29 "B.CrtYd" user "B.Courtyard")
		(35 "F.Fab" user)
		(33 "B.Fab" user)
	)
	(footprint "antmicro-footprints:EPT_401-51501-51"
		(layer "F.Cu")
		(at 203.275 159.81)
		(property "Reference" "J12"
			(at 30.975 -10.45 0)
			(layer "F.SilkS")
			(effects
				(font
					(size 0.7 0.7)
					(thickness 0.15)
				)
				(justify right top)
			)
		)
		(property "Value" "Plug_Bus_CE7_EPT_401-51501-51"
			(at -3.225 52.665 0)
			(layer "F.Fab")
			(hide yes)
			(effects
				(font
					(size 0.7 0.7)
					(thickness 0.15)
				)
				(justify left top)
			)
		)
		(property "Datasheet" "https://www.farnell.com/datasheets/1905093.pdf"
			(at 0 0 0)
			(layer "F.Fab")
			(hide yes)
			(effects
				(font
					(size 1.27 1.27)
					(thickness 0.15)
				)
			)
		)
		(property "Author" "Antmicro"
			(at 406.55 319.62 0)
			(layer "F.Fab")
			(hide yes)
			(effects
				(font
					(size 1 1)
					(thickness 0.15)
				)
			)
		)
		(property "License" "Apache-2.0"
			(at 406.55 319.62 0)
			(layer "F.Fab")
			(hide yes)
			(effects
				(font
					(size 1 1)
					(thickness 0.15)
				)
			)
		)
		(property "MPN" "401-51501-51"
			(at 406.55 319.62 0)
			(layer "F.Fab")
			(hide yes)
			(effects
				(font
					(size 1 1)
					(thickness 0.15)
				)
			)
		)
		(property "Manufacturer" "ept"
			(at 406.55 319.62 0)
			(layer "F.Fab")
			(hide yes)
			(effects
				(font
					(size 1 1)
					(thickness 0.15)
				)
			)
		)
		(sheetname "Com Express 7 Interfaces")
		(sheetfile "com_express_7_interfaces.kicad_sch")
		(attr smd)
		(pad "B90" smd rect
			(at 17.25 3.325)
			(size 0.3 1.75)
			(layers "F.Cu" "F.Mask" "F.Paste")
			(net 1 "GND")
			(pinfunction "GND(FIXED)")
			(pintype "passive")
			(teardrops
				(best_length_ratio 0.2)
				(max_length 1)
				(best_width_ratio 0.9)
				(max_width 2)
				(curved_edges yes)
				(filter_ratio 0.9)
				(enabled yes)
				(allow_two_segments yes)
				(prefer_zone_connections yes)
			)
		)
		(pad "B91" smd rect
			(at 17.75 3.325)
			(size 0.3 1.75)
			(layers "F.Cu" "F.Mask" "F.Paste")
			(net 391 "unconnected-(J12A-NCSI_CLK_IN-PadB91)")
			(pinfunction "NCSI_CLK_IN")
			(pintype "input+no_connect")
			(teardrops
				(best_length_ratio 0.2)
				(max_length 1)
				(best_width_ratio 0.9)
				(max_width 2)
				(curved_edges yes)
				(filter_ratio 0.9)
				(enabled yes)
				(allow_two_segments yes)
				(prefer_zone_connections yes)
			)
		)
		(pad "B92" smd rect
			(at 18.25 3.325)
			(size 0.3 1.75)
			(layers "F.Cu" "F.Mask" "F.Paste")
			(net 392 "unconnected-(J12A-NCSI_RXD1-PadB92)")
			(pinfunction "NCSI_RXD1")
			(pintype "input+no_connect")
			(teardrops
				(best_length_ratio 0.2)
				(max_length 1)
				(best_width_ratio 0.9)
				(max_width 2)
				(curved_edges yes)
				(filter_ratio 0.9)
				(enabled yes)
				(allow_two_segments yes)
				(prefer_zone_connections yes)
			)
		)
		(pad "B93" smd rect
			(at 18.75 3.325)
			(size 0.3 1.75)
			(layers "F.Cu" "F.Mask" "F.Paste")
			(net 393 "unconnected-(J12A-NCSI_RXD0-PadB93)")
			(pinfunction "NCSI_RXD0")
			(pintype "input+no_connect")
			(teardrops
				(best_length_ratio 0.2)
				(max_length 1)
				(best_width_ratio 0.9)
				(max_width 2)
				(curved_edges yes)
				(filter_ratio 0.9)
				(enabled yes)
				(allow_two_segments yes)
				(prefer_zone_connections yes)
			)
		)
		(pad "B94" smd rect
			(at 19.25 3.325)
			(size 0.3 1.75)
			(layers "F.Cu" "F.Mask" "F.Paste")
			(net 394 "unconnected-(J12A-NCSI_CRS_DV-PadB94)")
			(pinfunction "NCSI_CRS_DV")
			(pintype "output+no_connect")
			(teardrops
				(best_length_ratio 0.2)
				(max_length 1)
				(best_width_ratio 0.9)
				(max_width 2)
				(curved_edges yes)
				(filter_ratio 0.9)
				(enabled yes)
				(allow_two_segments yes)
				(prefer_zone_connections yes)
			)
		)
		(pad "B95" smd rect
			(at 19.75 3.325)
			(size 0.3 1.75)
			(layers "F.Cu" "F.Mask" "F.Paste")
			(net 395 "unconnected-(J12A-NCSI_TXD1-PadB95)")
			(pinfunction "NCSI_TXD1")
			(pintype "output+no_connect")
			(teardrops
				(best_length_ratio 0.2)
				(max_length 1)
				(best_width_ratio 0.9)
				(max_width 2)
				(curved_edges yes)
				(filter_ratio 0.9)
				(enabled yes)
				(allow_two_segments yes)
				(prefer_zone_connections yes)
			)
		)
		(pad "B96" smd rect
			(at 20.25 3.325)
			(size 0.3 1.75)
			(layers "F.Cu" "F.Mask" "F.Paste")
			(net 396 "unconnected-(J12A-NCSI_TXD0-PadB96)")
			(pinfunction "NCSI_TXD0")
			(pintype "output+no_connect")
			(teardrops
				(best_length_ratio 0.2)
				(max_length 1)
				(best_width_ratio 0.9)
				(max_width 2)
				(curved_edges yes)
				(filter_ratio 0.9)
				(enabled yes)
				(allow_two_segments yes)
				(prefer_zone_connections yes)
			)
		)
		(pad "B97" smd rect
			(at 20.75 3.325)
			(size 0.3 1.75)
			(layers "F.Cu" "F.Mask" "F.Paste")
			(net 397 "/Com Express 7 MGMT/SPI.~{CS}")
			(pinfunction "~{SPI_CS}")
			(pintype "output")
			(teardrops
				(best_length_ratio 0.2)
				(max_length 1)
				(best_width_ratio 0.9)
				(max_width 2)
				(curved_edges yes)
				(filter_ratio 0.9)
				(enabled yes)
				(allow_two_segments yes)
				(prefer_zone_connections yes)
			)
		)
		(pad "B98" smd rect
			(at 21.25 3.325)
			(size 0.3 1.75)
			(layers "F.Cu" "F.Mask" "F.Paste")
			(net 398 "unconnected-(J12A-NCSI_ARB_IN-PadB98)")
			(pinfunction "NCSI_ARB_IN")
			(pintype "input+no_connect")
			(teardrops
				(best_length_ratio 0.2)
				(max_length 1)
				(best_width_ratio 0.9)
				(max_width 2)
				(curved_edges yes)
				(filter_ratio 0.9)
				(enabled yes)
				(allow_two_segments yes)
				(prefer_zone_connections yes)
			)
		)
		(pad "B99" smd rect
			(at 21.75 3.325)
			(size 0.3 1.75)
			(layers "F.Cu" "F.Mask" "F.Paste")
			(net 399 "unconnected-(J12A-NCSI_ARB_OUT-PadB99)")
			(pinfunction "NCSI_ARB_OUT")
			(pintype "output+no_connect")
			(teardrops
				(best_length_ratio 0.2)
				(max_length 1)
				(best_width_ratio 0.9)
				(max_width 2)
				(curved_edges yes)
				(filter_ratio 0.9)
				(enabled yes)
				(allow_two_segments yes)
				(prefer_zone_connections yes)
			)
		)
		(pad "B100" smd rect
			(at 22.25 3.325)
			(size 0.3 1.75)
			(layers "F.Cu" "F.Mask" "F.Paste")
			(net 1 "GND")
			(pinfunction "GND(FIXED)")
			(pintype "passive")
			(teardrops
				(best_length_ratio 0.2)
				(max_length 1)
				(best_width_ratio 0.9)
				(max_width 2)
				(curved_edges yes)
				(filter_ratio 0.9)
				(enabled yes)
				(allow_two_segments yes)
				(prefer_zone_connections yes)
			)
		)
		(pad "B101" smd rect
			(at 22.75 3.325)
			(size 0.3 1.75)
			(layers "F.Cu" "F.Mask" "F.Paste")
			(net 400 "/Com Express 7 MGMT/FAN_PWM")
			(pinfunction "FAN_PWMOUT")
			(pintype "output")
			(teardrops
				(best_length_ratio 0.2)
				(max_length 1)
				(best_width_ratio 0.9)
				(max_width 2)
				(curved_edges yes)
				(filter_ratio 0.9)
				(enabled yes)
				(allow_two_segments yes)
				(prefer_zone_connections yes)
			)
		)
		(pad "B102" smd rect
			(at 23.25 3.325)
			(size 0.3 1.75)
			(layers "F.Cu" "F.Mask" "F.Paste")
			(net 401 "/Com Express 7 MGMT/FAM_TACH")
			(pinfunction "FAN_TACHIN")
			(pintype "input")
			(teardrops
				(best_length_ratio 0.2)
				(max_length 1)
				(best_width_ratio 0.9)
				(max_width 2)
				(curved_edges yes)
				(filter_ratio 0.9)
				(enabled yes)
				(allow_two_segments yes)
				(prefer_zone_connections yes)
			)
		)
		(pad "B103" smd rect
			(at 23.75 3.325)
			(size 0.3 1.75)
			(layers "F.Cu" "F.Mask" "F.Paste")
			(net 402 "unconnected-(J12D-~{SLEEP}-PadB103)")
			(pinfunction "~{SLEEP}")
			(pintype "input+no_connect")
			(teardrops
				(best_length_ratio 0.2)
				(max_length 1)
				(best_width_ratio 0.9)
				(max_width 2)
				(curved_edges yes)
				(filter_ratio 0.9)
				(enabled yes)
				(allow_two_segments yes)
				(prefer_zone_connections yes)
			)
		)
		(pad "B104" smd rect
			(at 24.25 3.325)
			(size 0.3 1.75)
			(layers "F.Cu" "F.Mask" "F.Paste")
			(net 65 "+12V")
			(pinfunction "VCC_12V")
			(pintype "passive")
			(teardrops
				(best_length_ratio 0.2)
				(max_length 1)
				(best_width_ratio 0.9)
				(max_width 2)
				(curved_edges yes)
				(filter_ratio 0.9)
				(enabled yes)
				(allow_two_segments yes)
				(prefer_zone_connections yes)
			)
		)
		(pad "B105" smd rect
			(at 24.75 3.325)
			(size 0.3 1.75)
			(layers "F.Cu" "F.Mask" "F.Paste")
			(net 65 "+12V")
			(pinfunction "VCC_12V")
			(pintype "passive")
			(teardrops
				(best_length_ratio 0.2)
				(max_length 1)
				(best_width_ratio 0.9)
				(max_width 2)
				(curved_edges yes)
				(filter_ratio 0.9)
				(enabled yes)
				(allow_two_segments yes)
				(prefer_zone_connections yes)
			)
		)
		(pad "B106" smd rect
			(at 25.25 3.325)
			(size 0.3 1.75)
			(layers "F.Cu" "F.Mask" "F.Paste")
			(net 65 "+12V")
			(pinfunction "VCC_12V")
			(pintype "passive")
			(teardrops
				(best_length_ratio 0.2)
				(max_length 1)
				(best_width_ratio 0.9)
				(max_width 2)
				(curved_edges yes)
				(filter_ratio 0.9)
				(enabled yes)
				(allow_two_segments yes)
				(prefer_zone_connections yes)
			)
		)
		(pad "B107" smd rect
			(at 25.75 3.325)
			(size 0.3 1.75)
			(layers "F.Cu" "F.Mask" "F.Paste")
			(net 65 "+12V")
			(pinfunction "VCC_12V")
			(pintype "passive")
			(teardrops
				(best_length_ratio 0.2)
				(max_length 1)
				(best_width_ratio 0.9)
				(max_width 2)
				(curved_edges yes)
				(filter_ratio 0.9)
				(enabled yes)
				(allow_two_segments yes)
				(prefer_zone_connections yes)
			)
		)
		(pad "B108" smd rect
			(at 26.25 3.325)
			(size 0.3 1.75)
			(layers "F.Cu" "F.Mask" "F.Paste")
			(net 65 "+12V")
			(pinfunction "VCC_12V")
			(pintype "passive")
			(teardrops
				(best_length_ratio 0.2)
				(max_length 1)
				(best_width_ratio 0.9)
				(max_width 2)
				(curved_edges yes)
				(filter_ratio 0.9)
				(enabled yes)
				(allow_two_segments yes)
				(prefer_zone_connections yes)
			)
		)
		(pad "B109" smd rect
			(at 26.75 3.325)
			(size 0.3 1.75)
			(layers "F.Cu" "F.Mask" "F.Paste")
			(net 65 "+12V")
			(pinfunction "VCC_12V")
			(pintype "passive")
			(teardrops
				(best_length_ratio 0.2)
				(max_length 1)
				(best_width_ratio 0.9)
				(max_width 2)
				(curved_edges yes)
				(filter_ratio 0.9)
				(enabled yes)
				(allow_two_segments yes)
				(prefer_zone_connections yes)
			)
		)
		(pad "B110" smd rect
			(at 27.25 3.325)
			(size 0.3 1.75)
			(layers "F.Cu" "F.Mask" "F.Paste")
			(net 1 "GND")
			(pinfunction "GND(FIXED)")
			(pintype "passive")
			(teardrops
				(best_length_ratio 0.2)
				(max_length 1)
				(best_width_ratio 0.9)
				(max_width 2)
				(curved_edges yes)
				(filter_ratio 0.9)
				(enabled yes)
				(allow_two_segments yes)
				(prefer_zone_connections yes)
			)
		)
		(pad "C1" smd rect
			(at -27.25 -3.125)
			(size 0.3 1.75)
			(layers "F.Cu" "F.Mask" "F.Paste")
			(net 1 "GND")
			(pinfunction "GND(FIXED)")
			(pintype "power_in")
			(teardrops
				(best_length_ratio 0.2)
				(max_length 1)
				(best_width_ratio 0.9)
				(max_width 2)
				(curved_edges yes)
				(filter_ratio 0.9)
				(enabled yes)
				(allow_two_segments yes)
				(prefer_zone_connections yes)
			)
		)
		(pad "C2" smd rect
			(at -26.75 -3.125)
			(size 0.3 1.75)
			(layers "F.Cu" "F.Mask" "F.Paste")
			(net 1 "GND")
			(pinfunction "GND")
			(pintype "passive")
			(teardrops
				(best_length_ratio 0.2)
				(max_length 1)
				(best_width_ratio 0.9)
				(max_width 2)
				(curved_edges yes)
				(filter_ratio 0.9)
				(enabled yes)
				(allow_two_segments yes)
				(prefer_zone_connections yes)
			)
		)
		(pad "C3" smd rect
			(at -26.25 -3.125)
			(size 0.3 1.75)
			(layers "F.Cu" "F.Mask" "F.Paste")
			(net 403 "unconnected-(J12J-USB_SSRX0--PadC3)")
			(pinfunction "USB_SSRX0-")
			(pintype "input+no_connect")
			(teardrops
				(best_length_ratio 0.2)
				(max_length 1)
				(best_width_ratio 0.9)
				(max_width 2)
				(curved_edges yes)
				(filter_ratio 0.9)
				(enabled yes)
				(allow_two_segments yes)
				(prefer_zone_connections yes)
			)
		)
		(pad "C4" smd rect
			(at -25.75 -3.125)
			(size 0.3 1.75)
			(layers "F.Cu" "F.Mask" "F.Paste")
			(net 404 "unconnected-(J12J-USB_SSRX0+-PadC4)")
			(pinfunction "USB_SSRX0+")
			(pintype "input+no_connect")
			(teardrops
				(best_length_ratio 0.2)
				(max_length 1)
				(best_width_ratio 0.9)
				(max_width 2)
				(curved_edges yes)
				(filter_ratio 0.9)
				(enabled yes)
				(allow_two_segments yes)
				(prefer_zone_connections yes)
			)
		)
		(pad "C5" smd rect
			(at -25.25 -3.125)
			(size 0.3 1.75)
			(layers "F.Cu" "F.Mask" "F.Paste")
			(net 1 "GND")
			(pinfunction "GND")
			(pintype "passive")
			(teardrops
				(best_length_ratio 0.2)
				(max_length 1)
				(best_width_ratio 0.9)
				(max_width 2)
				(curved_edges yes)
				(filter_ratio 0.9)
				(enabled yes)
				(allow_two_segments yes)
				(prefer_zone_connections yes)
			)
		)
		(pad "C6" smd rect
			(at -24.75 -3.125)
			(size 0.3 1.75)
			(layers "F.Cu" "F.Mask" "F.Paste")
			(net 405 "unconnected-(J12J-USB_SSRX1--PadC6)")
			(pinfunction "USB_SSRX1-")
			(pintype "input+no_connect")
			(teardrops
				(best_length_ratio 0.2)
				(max_length 1)
				(best_width_ratio 0.9)
				(max_width 2)
				(curved_edges yes)
				(filter_ratio 0.9)
				(enabled yes)
				(allow_two_segments yes)
				(prefer_zone_connections yes)
			)
		)
		(pad "C7" smd rect
			(at -24.25 -3.125)
			(size 0.3 1.75)
			(layers "F.Cu" "F.Mask" "F.Paste")
			(net 406 "unconnected-(J12J-USB_SSRX1+-PadC7)")
			(pinfunction "USB_SSRX1+")
			(pintype "input+no_connect")
			(teardrops
				(best_length_ratio 0.2)
				(max_length 1)
				(best_width_ratio 0.9)
				(max_width 2)
				(curved_edges yes)
				(filter_ratio 0.9)
				(enabled yes)
				(allow_two_segments yes)
				(prefer_zone_connections yes)
			)
		)
		(pad "C8" smd rect
			(at -23.75 -3.125)
			(size 0.3 1.75)
			(layers "F.Cu" "F.Mask" "F.Paste")
			(net 1 "GND")
			(pinfunction "GND")
			(pintype "passive")
			(teardrops
				(best_length_ratio 0.2)
				(max_length 1)
				(best_width_ratio 0.9)
				(max_width 2)
				(curved_edges yes)
				(filter_ratio 0.9)
				(enabled yes)
				(allow_two_segments yes)
				(prefer_zone_connections yes)
			)
		)
		(pad "C9" smd rect
			(at -23.25 -3.125)
			(size 0.3 1.75)
			(layers "F.Cu" "F.Mask" "F.Paste")
			(net 158 "/2xUSB3.0+RJ45/USBSS_1.RX-")
			(pinfunction "USB_SSRX2-")
			(pintype "input")
			(teardrops
				(best_length_ratio 0.2)
				(max_length 1)
				(best_width_ratio 0.9)
				(max_width 2)
				(curved_edges yes)
				(filter_ratio 0.9)
				(enabled yes)
				(allow_two_segments yes)
				(prefer_zone_connections yes)
			)
		)
		(pad "C10" smd rect
			(at -22.75 -3.125)
			(size 0.3 1.75)
			(layers "F.Cu" "F.Mask" "F.Paste")
			(net 159 "/2xUSB3.0+RJ45/USBSS_1.RX+")
			(pinfunction "USB_SSRX2+")
			(pintype "input")
			(teardrops
				(best_length_ratio 0.2)
				(max_length 1)
				(best_width_ratio 0.9)
				(max_width 2)
				(curved_edges yes)
				(filter_ratio 0.9)
				(enabled yes)
				(allow_two_segments yes)
				(prefer_zone_connections yes)
			)
		)
		(pad "C11" smd rect
			(at -22.25 -3.125)
			(size 0.3 1.75)
			(layers "F.Cu" "F.Mask" "F.Paste")
			(net 1 "GND")
			(pinfunction "GND(FIXED)")
			(pintype "passive")
			(teardrops
				(best_length_ratio 0.2)
				(max_length 1)
				(best_width_ratio 0.9)
				(max_width 2)
				(curved_edges yes)
				(filter_ratio 0.9)
				(enabled yes)
				(allow_two_segments yes)
				(prefer_zone_connections yes)
			)
		)
		(pad "C12" smd rect
			(at -21.75 -3.125)
			(size 0.3 1.75)
			(layers "F.Cu" "F.Mask" "F.Paste")
			(net 160 "/2xUSB3.0+RJ45/USBSS_2.RX-")
			(pinfunction "USB_SSRX3-")
			(pintype "input")
			(teardrops
				(best_length_ratio 0.2)
				(max_length 1)
				(best_width_ratio 0.9)
				(max_width 2)
				(curved_edges yes)
				(filter_ratio 0.9)
				(enabled yes)
				(allow_two_segments yes)
				(prefer_zone_connections yes)
			)
		)
		(pad "C13" smd rect
			(at -21.25 -3.125)
			(size 0.3 1.75)
			(layers "F.Cu" "F.Mask" "F.Paste")
			(net 161 "/2xUSB3.0+RJ45/USBSS_2.RX+")
			(pinfunction "USB_SSRX3+")
			(pintype "input")
			(teardrops
				(best_length_ratio 0.2)
				(max_length 1)
				(best_width_ratio 0.9)
				(max_width 2)
				(curved_edges yes)
				(filter_ratio 0.9)
				(enabled yes)
				(allow_two_segments yes)
				(prefer_zone_connections yes)
			)
		)
		(pad "C14" smd rect
			(at -20.75 -3.125)
			(size 0.3 1.75)
			(layers "F.Cu" "F.Mask" "F.Paste")
			(net 1 "GND")
			(pinfunction "GND")
			(pintype "passive")
			(teardrops
				(best_length_ratio 0.2)
				(max_length 1)
				(best_width_ratio 0.9)
				(max_width 2)
				(curved_edges yes)
				(filter_ratio 0.9)
				(enabled yes)
				(allow_two_segments yes)
				(prefer_zone_connections yes)
			)
		)
		(pad "C15" smd rect
			(at -20.25 -3.125)
			(size 0.3 1.75)
			(layers "F.Cu" "F.Mask" "F.Paste")
			(net 407 "unconnected-(J12K-10G_PHY_MDC_SCL3-PadC15)")
			(pinfunction "10G_PHY_MDC_SCL3")
			(pintype "open_collector+no_connect")
			(teardrops
				(best_length_ratio 0.2)
				(max_length 1)
				(best_width_ratio 0.9)
				(max_width 2)
				(curved_edges yes)
				(filter_ratio 0.9)
				(enabled yes)
				(allow_two_segments yes)
				(prefer_zone_connections yes)
			)
		)
		(pad "C16" smd rect
			(at -19.75 -3.125)
			(size 0.3 1.75)
			(layers "F.Cu" "F.Mask" "F.Paste")
			(net 408 "unconnected-(J12K-10G_PHY_MDC_SCL2-PadC16)")
			(pinfunction "10G_PHY_MDC_SCL2")
			(pintype "open_collector+no_connect")
			(teardrops
				(best_length_ratio 0.2)
				(max_length 1)
				(best_width_ratio 0.9)
				(max_width 2)
				(curved_edges yes)
				(filter_ratio 0.9)
				(enabled yes)
				(allow_two_segments yes)
				(prefer_zone_connections yes)
			)
		)
		(pad "C17" smd rect
			(at -19.25 -3.125)
			(size 0.3 1.75)
			(layers "F.Cu" "F.Mask" "F.Paste")
			(net 409 "Net-(J12K-10G_SDP2)")
			(pinfunction "10G_SDP2")
			(pintype "bidirectional")
			(teardrops
				(best_length_ratio 0.2)
				(max_length 1)
				(best_width_ratio 0.9)
				(max_width 2)
				(curved_edges yes)
				(filter_ratio 0.9)
				(enabled yes)
				(allow_two_segments yes)
				(prefer_zone_connections yes)
			)
		)
		(pad "C18" smd rect
			(at -18.75 -3.125)
			(size 0.3 1.75)
			(layers "F.Cu" "F.Mask" "F.Paste")
			(net 1 "GND")
			(pinfunction "GND")
			(pintype "passive")
			(teardrops
				(best_length_ratio 0.2)
				(max_length 1)
				(best_width_ratio 0.9)
				(max_width 2)
				(curved_edges yes)
				(filter_ratio 0.9)
				(enabled yes)
				(allow_two_segments yes)
				(prefer_zone_connections yes)
			)
		)
		(pad "C19" smd rect
			(at -18.25 -3.125)
			(size 0.3 1.75)
			(layers "F.Cu" "F.Mask" "F.Paste")
			(net 410 "unconnected-(J12O-PCIE_RX6+-PadC19)")
			(pinfunction "PCIE_RX6+")
			(pintype "input+no_connect")
			(teardrops
				(best_length_ratio 0.2)
				(max_length 1)
				(best_width_ratio 0.9)
				(max_width 2)
				(curved_edges yes)
				(filter_ratio 0.9)
				(enabled yes)
				(allow_two_segments yes)
				(prefer_zone_connections yes)
			)
		)
		(pad "C20" smd rect
			(at -17.75 -3.125)
			(size 0.3 1.75)
			(layers "F.Cu" "F.Mask" "F.Paste")
			(net 411 "unconnected-(J12O-PCIE_RX6--PadC20)")
			(pinfunction "PCIE_RX6-")
			(pintype "input+no_connect")
			(teardrops
				(best_length_ratio 0.2)
				(max_length 1)
				(best_width_ratio 0.9)
				(max_width 2)
				(curved_edges yes)
				(filter_ratio 0.9)
				(enabled yes)
				(allow_two_segments yes)
				(prefer_zone_connections yes)
			)
		)
	)
)
